(kicad_pcb
	(version 20260206)
	(generator "pcbnew")
	(generator_version "10.0")
	(general
		(thickness 1.6)
		(legacy_teardrops no)
	)
	(paper "A4")
	(title_block
		(title "Wiwynn_Tioga_Pass_MB.brd")
		(comment 1 "Tioga Pass / footprints 601-608 of 4770")
	)
	(layers
		(0 "F.Cu" signal "TOP")
		(4 "In1.Cu" signal "L2GND")
		(6 "In2.Cu" signal "L3")
		(8 "In3.Cu" signal "L4GND")
		(10 "In4.Cu" signal "L5")
		(12 "In5.Cu" signal "L6GND")
		(14 "In6.Cu" signal "L7VCC")
		(16 "In7.Cu" signal "L8VCC")
		(18 "In8.Cu" signal "L9GND")
		(20 "In9.Cu" signal "L10")
		(22 "In10.Cu" signal "L11GND")
		(24 "In11.Cu" signal "L12")
		(26 "In12.Cu" signal "L13GND")
		(2 "B.Cu" signal "BOTTOM")
		(9 "F.Adhes" user "F.Adhesive")
		(11 "B.Adhes" user "B.Adhesive")
		(13 "F.Paste" user "Package Geometry/Pastemask Top")
		(15 "B.Paste" user "Package Geometry/Pastemask Bottom")
		(5 "F.SilkS" user "Ref Des/Silkscreen Top")
		(7 "B.SilkS" user "Ref Des/Silkscreen Bottom")
		(1 "F.Mask" user "Board Geometry/Soldermask Top")
		(3 "B.Mask" user "Board Geometry/Soldermask Bottom")
		(17 "Dwgs.User" user "User.Drawings")
		(19 "Cmts.User" user "User.Comments")
		(21 "Eco1.User" user "User.Eco1")
		(23 "Eco2.User" user "User.Eco2")
		(25 "Edge.Cuts" user "Board Geometry/Outline")
		(27 "Margin" user)
		(31 "F.CrtYd" user "Package Geometry/Place Bound Top")
		(29 "B.CrtYd" user "Package Geometry/Place Bound Bottom")
		(35 "F.Fab" user "Ref Des/Assembly Top")
		(33 "B.Fab" user "Ref Des/Assembly Bottom")
	)
	(footprint ""
		(layer "F.Cu")
		(at 353.387914 -134.222744 180)
		(property "Reference" "R3M1"
			(at 0 0 180)
			(layer "F.SilkS")
			(hide yes)
			(effects
				(font
					(size 1.27 1.27)
				)
			)
		)
		(property "Value" ""
			(at 0 0 180)
			(layer "F.Fab")
			(effects
				(font
					(size 1.27 1.27)
				)
			)
		)
		(duplicate_pad_numbers_are_jumpers no)
		(fp_rect
			(start -0.2794 -0.1016)
			(end 0.2794 0.9906)
			(stroke
				(width 0)
				(type default)
			)
			(fill no)
			(layer "F.CrtYd")
		)
		(fp_line
			(start 0.2794 0.9906)
			(end 0.2794 -0.1016)
			(stroke
				(width 0.1)
				(type default)
			)
			(layer "F.Fab")
		)
		(fp_line
			(start 0.2794 -0.1016)
			(end -0.2794 -0.1016)
			(stroke
				(width 0.1)
				(type default)
			)
			(layer "F.Fab")
		)
		(fp_line
			(start -0.2794 0.9906)
			(end 0.2794 0.9906)
			(stroke
				(width 0.1)
				(type default)
			)
			(layer "F.Fab")
		)
		(fp_line
			(start -0.2794 -0.1016)
			(end -0.2794 0.9906)
			(stroke
				(width 0.1)
				(type default)
			)
			(layer "F.Fab")
		)
		(pad "1" smd rect
			(at 0 0 180)
			(size 0.508 0.508)
			(layers "F.Cu" "F.Mask" "F.Paste")
			(net "P3V3_STBY")
		)
		(pad "2" smd rect
			(at 0 0.889 180)
			(size 0.508 0.508)
			(layers "F.Cu" "F.Mask" "F.Paste")
			(net "VR_PVDDQ_DEF_VDD")
		)
		(zone
			(layer "F.Cu")
			(hatch none 0.5)
			(connect_pads
				(clearance 0)
			)
			(min_thickness 0.25)
			(keepout
				(tracks allowed)
				(vias not_allowed)
				(pads allowed)
				(copperpour not_allowed)
				(footprints allowed)
			)
			(placement
				(enabled no)
				(sheetname "")
			)
			(fill
				(thermal_gap 0.5)
				(thermal_bridge_width 0.5)
				(island_removal_mode 0)
			)
			(polygon
				(pts
					(xy 353.641914 -134.476744) (xy 353.641914 -134.857744) (xy 353.133914 -134.857744) (xy 353.133914 -134.476744)
				)
			)
		)
		(zone
			(layer "F.Cu")
			(hatch none 0.5)
			(connect_pads
				(clearance 0)
			)
			(min_thickness 0.25)
			(keepout
				(tracks not_allowed)
				(vias allowed)
				(pads allowed)
				(copperpour not_allowed)
				(footprints allowed)
			)
			(placement
				(enabled no)
				(sheetname "")
			)
			(fill
				(thermal_gap 0.5)
				(thermal_bridge_width 0.5)
				(island_removal_mode 0)
			)
			(polygon
				(pts
					(xy 353.641914 -134.476744) (xy 353.641914 -134.857744) (xy 353.133914 -134.857744) (xy 353.133914 -134.476744)
				)
			)
		)
	)
	(footprint ""
		(layer "F.Cu")
		(at 400.558 -154.19324 180)
		(property "Reference" "R8W2"
			(at -0.8382 -0.67818 180)
			(unlocked yes)
			(layer "F.SilkS")
			(effects
				(font
					(size 0.4064 0.254)
					(thickness 0.1524)
				)
				(justify left)
			)
		)
		(property "Value" ""
			(at 0 0 180)
			(layer "F.Fab")
			(effects
				(font
					(size 1.27 1.27)
				)
			)
		)
		(duplicate_pad_numbers_are_jumpers no)
		(fp_poly
			(pts
				(xy -0.2794 -0.1016) (xy 0.2794 -0.1016) (xy 0.2794 0.9906) (xy -0.2794 0.9906)
			)
			(stroke
				(width 0)
				(type default)
			)
			(fill no)
			(layer "F.CrtYd")
		)
		(fp_line
			(start 0.2794 0.9906)
			(end 0.2794 -0.1016)
			(stroke
				(width 0.1)
				(type default)
			)
			(layer "F.Fab")
		)
		(fp_line
			(start 0.2794 -0.1016)
			(end -0.2794 -0.1016)
			(stroke
				(width 0.1)
				(type default)
			)
			(layer "F.Fab")
		)
		(fp_line
			(start -0.2794 0.9906)
			(end 0.2794 0.9906)
			(stroke
				(width 0.1)
				(type default)
			)
			(layer "F.Fab")
		)
		(fp_line
			(start -0.2794 -0.1016)
			(end -0.2794 0.9906)
			(stroke
				(width 0.1)
				(type default)
			)
			(layer "F.Fab")
		)
		(pad "1" smd rect
			(at 0 0 180)
			(size 0.508 0.508)
			(layers "F.Cu" "F.Mask" "F.Paste")
			(net "PU_PVNN_PCH_VCLK")
		)
		(pad "2" smd rect
			(at 0 0.889 180)
			(size 0.508 0.508)
			(layers "F.Cu" "F.Mask" "F.Paste")
			(net "VR_PVNN_P1V05_PCH_VD12")
		)
		(zone
			(layer "F.Cu")
			(hatch none 0.5)
			(connect_pads
				(clearance 0)
			)
			(min_thickness 0.25)
			(keepout
				(tracks not_allowed)
				(vias allowed)
				(pads allowed)
				(copperpour not_allowed)
				(footprints allowed)
			)
			(placement
				(enabled no)
				(sheetname "")
			)
			(fill
				(thermal_gap 0.5)
				(thermal_bridge_width 0.5)
				(island_removal_mode 0)
			)
			(polygon
				(pts
					(xy 400.812 -154.82824) (xy 400.304 -154.82824) (xy 400.304 -154.44724) (xy 400.812 -154.44724)
				)
			)
		)
		(zone
			(layer "F.Cu")
			(hatch none 0.5)
			(connect_pads
				(clearance 0)
			)
			(min_thickness 0.25)
			(keepout
				(tracks allowed)
				(vias not_allowed)
				(pads allowed)
				(copperpour not_allowed)
				(footprints allowed)
			)
			(placement
				(enabled no)
				(sheetname "")
			)
			(fill
				(thermal_gap 0.5)
				(thermal_bridge_width 0.5)
				(island_removal_mode 0)
			)
			(polygon
				(pts
					(xy 400.812 -154.44724) (xy 400.304 -154.44724) (xy 400.304 -154.82824) (xy 400.812 -154.82824)
				)
			)
		)
	)
	(footprint ""
		(layer "F.Cu")
		(at 11.130026 -4.419854)
		(property "Reference" "R1G7"
			(at 0 0 0)
			(layer "F.SilkS")
			(hide yes)
			(effects
				(font
					(size 1.27 1.27)
				)
			)
		)
		(property "Value" ""
			(at 0 0 0)
			(layer "F.Fab")
			(effects
				(font
					(size 1.27 1.27)
				)
			)
		)
		(duplicate_pad_numbers_are_jumpers no)
		(fp_rect
			(start -0.2794 -0.1016)
			(end 0.2794 0.9906)
			(stroke
				(width 0)
				(type default)
			)
			(fill no)
			(layer "F.CrtYd")
		)
		(fp_line
			(start -0.2794 -0.1016)
			(end -0.2794 0.9906)
			(stroke
				(width 0.1)
				(type default)
			)
			(layer "F.Fab")
		)
		(fp_line
			(start -0.2794 0.9906)
			(end 0.2794 0.9906)
			(stroke
				(width 0.1)
				(type default)
			)
			(layer "F.Fab")
		)
		(fp_line
			(start 0.2794 -0.1016)
			(end -0.2794 -0.1016)
			(stroke
				(width 0.1)
				(type default)
			)
			(layer "F.Fab")
		)
		(fp_line
			(start 0.2794 0.9906)
			(end 0.2794 -0.1016)
			(stroke
				(width 0.1)
				(type default)
			)
			(layer "F.Fab")
		)
		(pad "1" smd rect
			(at 0 0)
			(size 0.508 0.508)
			(layers "F.Cu" "F.Mask" "F.Paste")
			(net "SVID_CLK1_CPU1_R")
		)
		(pad "2" smd rect
			(at 0 0.889)
			(size 0.508 0.508)
			(layers "F.Cu" "F.Mask" "F.Paste")
			(net "SVID_CLK_PVDDQ_GHJ")
		)
		(zone
			(layer "F.Cu")
			(hatch none 0.5)
			(connect_pads
				(clearance 0)
			)
			(min_thickness 0.25)
			(keepout
				(tracks allowed)
				(vias not_allowed)
				(pads allowed)
				(copperpour not_allowed)
				(footprints allowed)
			)
			(placement
				(enabled no)
				(sheetname "")
			)
			(fill
				(thermal_gap 0.5)
				(thermal_bridge_width 0.5)
				(island_removal_mode 0)
			)
			(polygon
				(pts
					(xy 10.876026 -4.165854) (xy 10.876026 -3.784854) (xy 11.384026 -3.784854) (xy 11.384026 -4.165854)
				)
			)
		)
		(zone
			(layer "F.Cu")
			(hatch none 0.5)
			(connect_pads
				(clearance 0)
			)
			(min_thickness 0.25)
			(keepout
				(tracks not_allowed)
				(vias allowed)
				(pads allowed)
				(copperpour not_allowed)
				(footprints allowed)
			)
			(placement
				(enabled no)
				(sheetname "")
			)
			(fill
				(thermal_gap 0.5)
				(thermal_bridge_width 0.5)
				(island_removal_mode 0)
			)
			(polygon
				(pts
					(xy 10.876026 -4.165854) (xy 10.876026 -3.784854) (xy 11.384026 -3.784854) (xy 11.384026 -4.165854)
				)
			)
		)
	)
	(footprint ""
		(layer "F.Cu")
		(at 163.576 -85.598 -90)
		(property "Reference" "R4D9"
			(at 0 0 270)
			(layer "F.SilkS")
			(hide yes)
			(effects
				(font
					(size 1.27 1.27)
				)
			)
		)
		(property "Value" ""
			(at 0 0 270)
			(layer "F.Fab")
			(effects
				(font
					(size 1.27 1.27)
				)
			)
		)
		(duplicate_pad_numbers_are_jumpers no)
		(fp_poly
			(pts
				(xy -0.2794 -0.1016) (xy 0.2794 -0.1016) (xy 0.2794 0.9906) (xy -0.2794 0.9906)
			)
			(stroke
				(width 0)
				(type default)
			)
			(fill no)
			(layer "F.CrtYd")
		)
		(fp_line
			(start -0.2794 0.9906)
			(end 0.2794 0.9906)
			(stroke
				(width 0.1)
				(type default)
			)
			(layer "F.Fab")
		)
		(fp_line
			(start 0.2794 0.9906)
			(end 0.2794 -0.1016)
			(stroke
				(width 0.1)
				(type default)
			)
			(layer "F.Fab")
		)
		(fp_line
			(start -0.2794 -0.1016)
			(end -0.2794 0.9906)
			(stroke
				(width 0.1)
				(type default)
			)
			(layer "F.Fab")
		)
		(fp_line
			(start 0.2794 -0.1016)
			(end -0.2794 -0.1016)
			(stroke
				(width 0.1)
				(type default)
			)
			(layer "F.Fab")
		)
		(pad "1" smd rect
			(at 0 0 270)
			(size 0.508 0.508)
			(layers "F.Cu" "F.Mask" "F.Paste")
			(net "CLK_100M_CPU1_BCLK2_R_DP")
		)
		(pad "2" smd rect
			(at 0 0.889 270)
			(size 0.508 0.508)
			(layers "F.Cu" "F.Mask" "F.Paste")
			(net "CLK_100M_CPU1_BCLK2_DP")
		)
		(zone
			(layer "F.Cu")
			(hatch none 0.5)
			(connect_pads
				(clearance 0)
			)
			(min_thickness 0.25)
			(keepout
				(tracks not_allowed)
				(vias allowed)
				(pads allowed)
				(copperpour not_allowed)
				(footprints allowed)
			)
			(placement
				(enabled no)
				(sheetname "")
			)
			(fill
				(thermal_gap 0.5)
				(thermal_bridge_width 0.5)
				(island_removal_mode 0)
			)
			(polygon
				(pts
					(xy 162.941 -85.852) (xy 162.941 -85.344) (xy 163.322 -85.344) (xy 163.322 -85.852)
				)
			)
		)
		(zone
			(layer "F.Cu")
			(hatch none 0.5)
			(connect_pads
				(clearance 0)
			)
			(min_thickness 0.25)
			(keepout
				(tracks allowed)
				(vias not_allowed)
				(pads allowed)
				(copperpour not_allowed)
				(footprints allowed)
			)
			(placement
				(enabled no)
				(sheetname "")
			)
			(fill
				(thermal_gap 0.5)
				(thermal_bridge_width 0.5)
				(island_removal_mode 0)
			)
			(polygon
				(pts
					(xy 163.322 -85.852) (xy 163.322 -85.344) (xy 162.941 -85.344) (xy 162.941 -85.852)
				)
			)
		)
	)
	(footprint ""
		(layer "F.Cu")
		(at 377.8123 -137.1092)
		(property "Reference" "C7A36"
			(at 0 0 0)
			(layer "F.SilkS")
			(hide yes)
			(effects
				(font
					(size 1.27 1.27)
				)
			)
		)
		(property "Value" ""
			(at 0 0 0)
			(layer "F.Fab")
			(effects
				(font
					(size 1.27 1.27)
				)
			)
		)
		(duplicate_pad_numbers_are_jumpers no)
		(fp_rect
			(start -0.4953 1.6002)
			(end 0.4953 -0.2032)
			(stroke
				(width 0)
				(type default)
			)
			(fill no)
			(layer "F.CrtYd")
		)
		(fp_line
			(start -0.4953 -0.2032)
			(end 0.4953 -0.2032)
			(stroke
				(width 0.1)
				(type default)
			)
			(layer "F.Fab")
		)
		(fp_line
			(start -0.4953 1.6002)
			(end -0.4953 -0.2032)
			(stroke
				(width 0.1)
				(type default)
			)
			(layer "F.Fab")
		)
		(fp_line
			(start 0.4953 -0.2032)
			(end 0.4953 1.6002)
			(stroke
				(width 0.1)
				(type default)
			)
			(layer "F.Fab")
		)
		(fp_line
			(start 0.4953 1.6002)
			(end -0.4953 1.6002)
			(stroke
				(width 0.1)
				(type default)
			)
			(layer "F.Fab")
		)
		(pad "1" smd rect
			(at 0 0)
			(size 0.762 0.889)
			(layers "F.Cu" "F.Mask" "F.Paste")
			(net "PVNN_PCH_STBY")
		)
		(pad "2" smd rect
			(at 0 1.397)
			(size 0.762 0.889)
			(layers "F.Cu" "F.Mask" "F.Paste")
			(net "GND")
		)
		(zone
			(layer "F.Cu")
			(hatch none 0.5)
			(connect_pads
				(clearance 0)
			)
			(min_thickness 0.25)
			(keepout
				(tracks not_allowed)
				(vias allowed)
				(pads allowed)
				(copperpour not_allowed)
				(footprints allowed)
			)
			(placement
				(enabled no)
				(sheetname "")
			)
			(fill
				(thermal_gap 0.5)
				(thermal_bridge_width 0.5)
				(island_removal_mode 0)
			)
			(polygon
				(pts
					(xy 377.4313 -136.1567) (xy 378.1933 -136.1567) (xy 378.1933 -136.6647) (xy 377.4313 -136.6647)
				)
			)
		)
	)
	(footprint ""
		(layer "F.Cu")
		(at 7.665212 -108.42117 90)
		(property "Reference" "C9M5"
			(at 0 0 90)
			(layer "F.SilkS")
			(hide yes)
			(effects
				(font
					(size 1.27 1.27)
				)
			)
		)
		(property "Value" ""
			(at 0 0 90)
			(layer "F.Fab")
			(effects
				(font
					(size 1.27 1.27)
				)
			)
		)
		(duplicate_pad_numbers_are_jumpers no)
		(fp_poly
			(pts
				(xy 0.3048 -0.1016) (xy 0.3048 0.9906) (xy -0.3048 0.9906) (xy -0.3048 -0.1016)
			)
			(stroke
				(width 0)
				(type default)
			)
			(fill no)
			(layer "F.CrtYd")
		)
		(fp_line
			(start 0.3048 -0.1016)
			(end -0.3048 -0.1016)
			(stroke
				(width 0.1)
				(type default)
			)
			(layer "F.Fab")
		)
		(fp_line
			(start -0.3048 -0.1016)
			(end -0.3048 0.9906)
			(stroke
				(width 0.1)
				(type default)
			)
			(layer "F.Fab")
		)
		(fp_line
			(start 0.3048 0.9906)
			(end 0.3048 -0.1016)
			(stroke
				(width 0.1)
				(type default)
			)
			(layer "F.Fab")
		)
		(fp_line
			(start -0.3048 0.9906)
			(end 0.3048 0.9906)
			(stroke
				(width 0.1)
				(type default)
			)
			(layer "F.Fab")
		)
		(pad "1" smd rect
			(at 0 0 90)
			(size 0.508 0.508)
			(layers "F.Cu" "F.Mask" "F.Paste")
			(net "P12V_FAN")
		)
		(pad "2" smd rect
			(at 0 0.889 90)
			(size 0.508 0.508)
			(layers "F.Cu" "F.Mask" "F.Paste")
			(net "GND")
		)
		(zone
			(layer "F.Cu")
			(hatch none 0.5)
			(connect_pads
				(clearance 0)
			)
			(min_thickness 0.25)
			(keepout
				(tracks allowed)
				(vias not_allowed)
				(pads allowed)
				(copperpour not_allowed)
				(footprints allowed)
			)
			(placement
				(enabled no)
				(sheetname "")
			)
			(fill
				(thermal_gap 0.5)
				(thermal_bridge_width 0.5)
				(island_removal_mode 0)
			)
			(polygon
				(pts
					(xy 7.919212 -108.16717) (xy 7.919212 -108.67517) (xy 8.300212 -108.67517) (xy 8.300212 -108.16717)
				)
			)
		)
		(zone
			(layer "F.Cu")
			(hatch none 0.5)
			(connect_pads
				(clearance 0)
			)
			(min_thickness 0.25)
			(keepout
				(tracks not_allowed)
				(vias allowed)
				(pads allowed)
				(copperpour not_allowed)
				(footprints allowed)
			)
			(placement
				(enabled no)
				(sheetname "")
			)
			(fill
				(thermal_gap 0.5)
				(thermal_bridge_width 0.5)
				(island_removal_mode 0)
			)
			(polygon
				(pts
					(xy 8.300212 -108.16717) (xy 8.300212 -108.67517) (xy 7.919212 -108.67517) (xy 7.919212 -108.16717)
				)
			)
		)
	)
	(footprint ""
		(layer "F.Cu")
		(at 385.2926 -0.254)
		(property "Reference" "R7G16"
			(at 0 0 0)
			(layer "F.SilkS")
			(hide yes)
			(effects
				(font
					(size 1.27 1.27)
				)
			)
		)
		(property "Value" ""
			(at 0 0 0)
			(layer "F.Fab")
			(effects
				(font
					(size 1.27 1.27)
				)
			)
		)
		(duplicate_pad_numbers_are_jumpers no)
		(fp_poly
			(pts
				(xy -0.2794 -0.1016) (xy 0.2794 -0.1016) (xy 0.2794 0.9906) (xy -0.2794 0.9906)
			)
			(stroke
				(width 0)
				(type default)
			)
			(fill no)
			(layer "F.CrtYd")
		)
		(fp_line
			(start -0.2794 -0.1016)
			(end -0.2794 0.9906)
			(stroke
				(width 0.1)
				(type default)
			)
			(layer "F.Fab")
		)
		(fp_line
			(start -0.2794 0.9906)
			(end 0.2794 0.9906)
			(stroke
				(width 0.1)
				(type default)
			)
			(layer "F.Fab")
		)
		(fp_line
			(start 0.2794 -0.1016)
			(end -0.2794 -0.1016)
			(stroke
				(width 0.1)
				(type default)
			)
			(layer "F.Fab")
		)
		(fp_line
			(start 0.2794 0.9906)
			(end 0.2794 -0.1016)
			(stroke
				(width 0.1)
				(type default)
			)
			(layer "F.Fab")
		)
		(pad "1" smd rect
			(at 0 0)
			(size 0.508 0.508)
			(layers "F.Cu" "F.Mask" "F.Paste")
			(net "JTAG_PCH_GBE_TDO")
		)
		(pad "2" smd rect
			(at 0 0.889)
			(size 0.508 0.508)
			(layers "F.Cu" "F.Mask" "F.Paste")
			(net "JTAG_TDO")
		)
		(zone
			(layer "F.Cu")
			(hatch none 0.5)
			(connect_pads
				(clearance 0)
			)
			(min_thickness 0.25)
			(keepout
				(tracks allowed)
				(vias not_allowed)
				(pads allowed)
				(copperpour not_allowed)
				(footprints allowed)
			)
			(placement
				(enabled no)
				(sheetname "")
			)
			(fill
				(thermal_gap 0.5)
				(thermal_bridge_width 0.5)
				(island_removal_mode 0)
			)
			(polygon
				(pts
					(xy 385.0386 0) (xy 385.5466 0) (xy 385.5466 0.381) (xy 385.0386 0.381)
				)
			)
		)
		(zone
			(layer "F.Cu")
			(hatch none 0.5)
			(connect_pads
				(clearance 0)
			)
			(min_thickness 0.25)
			(keepout
				(tracks not_allowed)
				(vias allowed)
				(pads allowed)
				(copperpour not_allowed)
				(footprints allowed)
			)
			(placement
				(enabled no)
				(sheetname "")
			)
			(fill
				(thermal_gap 0.5)
				(thermal_bridge_width 0.5)
				(island_removal_mode 0)
			)
			(polygon
				(pts
					(xy 385.0386 0.381) (xy 385.5466 0.381) (xy 385.5466 0) (xy 385.0386 0)
				)
			)
		)
	)
	(footprint ""
		(layer "F.Cu")
		(at -0.60706 -132.54736)
		(property "Reference" "R1B2"
			(at 0 0 0)
			(layer "F.SilkS")
			(hide yes)
			(effects
				(font
					(size 1.27 1.27)
				)
			)
		)
		(property "Value" ""
			(at 0 0 0)
			(layer "F.Fab")
			(effects
				(font
					(size 1.27 1.27)
				)
			)
		)
		(duplicate_pad_numbers_are_jumpers no)
		(fp_rect
			(start -0.2794 0.9906)
			(end 0.2794 -0.1016)
			(stroke
				(width 0)
				(type default)
			)
			(fill no)
			(layer "F.CrtYd")
		)
		(fp_line
			(start -0.2794 -0.1016)
			(end -0.2794 0.9906)
			(stroke
				(width 0.1)
				(type default)
			)
			(layer "F.Fab")
		)
		(fp_line
			(start -0.2794 0.9906)
			(end 0.2794 0.9906)
			(stroke
				(width 0.1)
				(type default)
			)
			(layer "F.Fab")
		)
		(fp_line
			(start 0.2794 -0.1016)
			(end -0.2794 -0.1016)
			(stroke
				(width 0.1)
				(type default)
			)
			(layer "F.Fab")
		)
		(fp_line
			(start 0.2794 0.9906)
			(end 0.2794 -0.1016)
			(stroke
				(width 0.1)
				(type default)
			)
			(layer "F.Fab")
		)
		(pad "1" smd rect
			(at 0 0)
			(size 0.508 0.508)
			(layers "F.Cu" "F.Mask" "F.Paste")
			(net "P3V3_STBY")
		)
		(pad "2" smd rect
			(at 0 0.889)
			(size 0.508 0.508)
			(layers "F.Cu" "F.Mask" "F.Paste")
			(net "PWRGD_PVDDQ_KLM_R")
		)
		(zone
			(layer "F.Cu")
			(hatch none 0.5)
			(connect_pads
				(clearance 0)
			)
			(min_thickness 0.25)
			(keepout
				(tracks not_allowed)
				(vias allowed)
				(pads allowed)
				(copperpour not_allowed)
				(footprints allowed)
			)
			(placement
				(enabled no)
				(sheetname "")
			)
			(fill
				(thermal_gap 0.5)
				(thermal_bridge_width 0.5)
				(island_removal_mode 0)
			)
			(polygon
				(pts
					(xy -0.86106 -131.91236) (xy -0.35306 -131.91236) (xy -0.35306 -132.29336) (xy -0.86106 -132.29336)
				)
			)
		)
		(zone
			(layer "F.Cu")
			(hatch none 0.5)
			(connect_pads
				(clearance 0)
			)
			(min_thickness 0.25)
			(keepout
				(tracks allowed)
				(vias not_allowed)
				(pads allowed)
				(copperpour not_allowed)
				(footprints allowed)
			)
			(placement
				(enabled no)
				(sheetname "")
			)
			(fill
				(thermal_gap 0.5)
				(thermal_bridge_width 0.5)
				(island_removal_mode 0)
			)
			(polygon
				(pts
					(xy -0.86106 -131.91236) (xy -0.35306 -131.91236) (xy -0.35306 -132.29336) (xy -0.86106 -132.29336)
				)
			)
		)
	)
)
